FILE_TYPE = MACRO_DRAWING;
SET COLOR_WIRE YELLOW;
SET COLOR_PROP MONO;
SET COLOR_DOT WHITE;
SET COLOR_ARC YELLOW;
SET COLOR_BODY GREEN;
SET COLOR_NOTE MONO;
SET PROP_DISPLAY VALUE;
SET PAGE_NUMBER P249;
FORCEADD OFFPAGE..1
(-7400 2150);
FORCEPROP 2 LAST $XR0 147 
J 0
(-7652 2150);
DISPLAY 0.638298 (-7652 2150);
PAINT MONO (-7652 2150);
FORCEPROP 2 LAST $XRERR ?
J 0
(-7796 2150);
DISPLAY 0.638298 (-7796 2150);
PAINT MONO (-7796 2150);
DISPLAY INVISIBLE (-7796 2150);
FORCEPROP 2 LAST $XRERR ?
J 0
(-7796 2150);
DISPLAY 0.638298 (-7796 2150);
PAINT MONO (-7796 2150);
DISPLAY INVISIBLE (-7796 2150);
FORCEPROP 2 LAST $XRERR ?
J 0
(-7796 2150);
DISPLAY 0.638298 (-7796 2150);
PAINT MONO (-7796 2150);
DISPLAY INVISIBLE (-7796 2150);
FORCEPROP 2 LAST $XRERR ?
J 0
(-7796 2150);
DISPLAY 0.638298 (-7796 2150);
PAINT MONO (-7796 2150);
DISPLAY INVISIBLE (-7796 2150);
FORCEPROP 2 LAST $XRERR ?
J 0
(-7796 2150);
DISPLAY 0.638298 (-7796 2150);
PAINT MONO (-7796 2150);
DISPLAY INVISIBLE (-7796 2150);
FORCEPROP 2 LAST PATH I1
J 0
(-7350 2225);
DISPLAY 1.021277 (-7350 2225);
PAINT ORANGE (-7350 2225);
DISPLAY INVISIBLE (-7350 2225);
FORCEPROP 1 LAST OFFPAGE TRUE
J 0
(-7075 2025);
DISPLAY 0.872340 (-7075 2025);
PAINT GREEN (-7075 2025);
DISPLAY INVISIBLE (-7075 2025);
FORCEPROP 1 LAST COMMENT_BODY TRUE
J 0
(-7275 2050);
DISPLAY 0.872340 (-7275 2050);
PAINT GREEN (-7275 2050);
DISPLAY INVISIBLE (-7275 2050);
FORCEPROP 2 LAST CDS_LIB mstr_standard
J 0
(-7400 2150);
PAINT MONO (-7400 2150);
DISPLAY INVISIBLE (-7400 2150);
FORCEPROP 2 LAST $XRERR ?
J 0
(-7796 2150);
DISPLAY 0.638298 (-7796 2150);
PAINT MONO (-7796 2150);
DISPLAY INVISIBLE (-7796 2150);
FORCEPROP 2 LAST $XRERR ?
J 0
(-7796 2150);
DISPLAY 0.638298 (-7796 2150);
PAINT MONO (-7796 2150);
DISPLAY INVISIBLE (-7796 2150);
FORCEPROP 2 LAST $XRERR ?
J 0
(-7796 2150);
DISPLAY 0.638298 (-7796 2150);
PAINT MONO (-7796 2150);
DISPLAY INVISIBLE (-7796 2150);
FORCEPROP 2 LAST $XRERR ?
J 0
(-7796 2150);
DISPLAY 0.638298 (-7796 2150);
PAINT MONO (-7796 2150);
DISPLAY INVISIBLE (-7796 2150);
FORCEPROP 2 LAST $XRERR ?
J 0
(-7796 2150);
DISPLAY 0.638298 (-7796 2150);
PAINT MONO (-7796 2150);
DISPLAY INVISIBLE (-7796 2150);
FORCEPROP 2 LAST $XRERR ?
J 0
(-7796 2150);
DISPLAY 0.638298 (-7796 2150);
PAINT MONO (-7796 2150);
DISPLAY INVISIBLE (-7796 2150);
FORCEPROP 2 LAST $XRERR ?
J 0
(-7796 2150);
DISPLAY 0.638298 (-7796 2150);
PAINT MONO (-7796 2150);
DISPLAY INVISIBLE (-7796 2150);
FORCEADD GND..1
(-4550 3625);
FORCEPROP 3 LASTPIN (-4550 3675) SIG_NAME GND\g
J 0
(-4540 3685);
DISPLAY 0.659574 (-4540 3685);
PAINT MONO (-4540 3685);
DISPLAY INVISIBLE (-4540 3685);
FORCEPROP 1 LAST HDL_POWER GND
J 0
(-4550 3775);
DISPLAY 0.872340 (-4550 3775);
PAINT GREEN (-4550 3775);
DISPLAY INVISIBLE (-4550 3775);
FORCEPROP 1 LAST SIZE 1B
J 0
(-4475 3575);
DISPLAY 0.872340 (-4475 3575);
PAINT AQUA (-4475 3575);
DISPLAY INVISIBLE (-4475 3575);
FORCEPROP 2 LAST CDS_LIB mstr_symbols
J 0
(-4550 3625);
PAINT MONO (-4550 3625);
DISPLAY INVISIBLE (-4550 3625);
FORCEPROP 1 LAST BODY_TYPE PLUMBING
J 0
(-4595 3582);
DISPLAY 0.340426 (-4595 3582);
PAINT GREEN (-4595 3582);
DISPLAY INVISIBLE (-4595 3582);
FORCEPROP 1 LAST VOLTAGE 0.0V
J 0
(-4595 3582);
DISPLAY 0.340426 (-4595 3582);
PAINT GREEN (-4595 3582);
DISPLAY INVISIBLE (-4595 3582);
FORCEPROP 1 LAST PATH I10
J 0
(-4475 3625);
DISPLAY 0.872340 (-4475 3625);
PAINT AQUA (-4475 3625);
DISPLAY INVISIBLE (-4475 3625);
FORCEADD GND..1
(-5875 1550);
FORCEPROP 3 LASTPIN (-5875 1600) SIG_NAME GND\g
J 0
(-5865 1610);
DISPLAY 0.659574 (-5865 1610);
PAINT MONO (-5865 1610);
DISPLAY INVISIBLE (-5865 1610);
FORCEPROP 2 LAST CDS_LIB mstr_symbols
J 0
(-5875 1550);
PAINT MONO (-5875 1550);
DISPLAY INVISIBLE (-5875 1550);
FORCEPROP 1 LAST HDL_POWER GND
J 0
(-5875 1700);
DISPLAY 0.872340 (-5875 1700);
PAINT GREEN (-5875 1700);
DISPLAY INVISIBLE (-5875 1700);
FORCEPROP 1 LAST SIZE 1B
J 0
(-5800 1500);
DISPLAY 0.872340 (-5800 1500);
PAINT AQUA (-5800 1500);
DISPLAY INVISIBLE (-5800 1500);
FORCEPROP 1 LAST BODY_TYPE PLUMBING
J 0
(-5920 1507);
DISPLAY 0.340426 (-5920 1507);
PAINT GREEN (-5920 1507);
DISPLAY INVISIBLE (-5920 1507);
FORCEPROP 1 LAST VOLTAGE 0.0V
J 0
(-5920 1507);
DISPLAY 0.340426 (-5920 1507);
PAINT GREEN (-5920 1507);
DISPLAY INVISIBLE (-5920 1507);
FORCEPROP 1 LAST PATH I11
J 0
(-5800 1550);
DISPLAY 0.872340 (-5800 1550);
PAINT AQUA (-5800 1550);
DISPLAY INVISIBLE (-5800 1550);
FORCEADD RES..2
(-6325 1925);
FORCEPROP 1 LAST PART_NUMBER G21796-026
J 0
(-6285 1800);
DISPLAY 0.617021 (-6285 1800);
PAINT BLUE (-6285 1800);
FORCEPROP 1 LAST WATTAGE 1/16W
J 0
(-6285 1900);
DISPLAY 0.617021 (-6285 1900);
PAINT SKYBLUE (-6285 1900);
FORCEPROP 1 LAST VALUE 1.00K
J 0
(-6280 2000);
DISPLAY 0.617021 (-6280 2000);
PAINT SKYBLUE (-6280 2000);
FORCEPROP 1 LAST PACK_TYPE 0402
J 0
(-6285 1750);
DISPLAY 0.617021 (-6285 1750);
PAINT SKYBLUE (-6285 1750);
FORCEPROP 1 LAST TOLERANCE 1%
J 0
(-6280 1950);
DISPLAY 0.617021 (-6280 1950);
PAINT SKYBLUE (-6280 1950);
FORCEPROP 1 LAST LOCATION R3W2
J 0
(-6280 2050);
DISPLAY 0.617021 (-6280 2050);
PAINT AQUA (-6280 2050);
FORCEPROP 1 LAST MATERIAL CHIP
J 0
(-6285 1850);
DISPLAY 0.617021 (-6285 1850);
PAINT SKYBLUE (-6285 1850);
FORCEPROP 0 LAST ROOM BMC_DEBUG_HEADER
J 0
(-6275 2150);
DISPLAY 1.021277 (-6275 2150);
PAINT ORANGE (-6275 2150);
DISPLAY INVISIBLE (-6275 2150);
FORCEPROP 2 LAST CDS_LIB mstr_discrete
J 0
(-6325 1925);
PAINT MONO (-6325 1925);
DISPLAY INVISIBLE (-6325 1925);
FORCEPROP 1 LAST PATH I12
J 0
(-6275 2100);
DISPLAY 0.978723 (-6275 2100);
PAINT WHITE (-6275 2100);
DISPLAY INVISIBLE (-6275 2100);
FORCEPROP 1 LASTPIN (-6325 1825) $PN 2
J 0
(-6320 1835);
DISPLAY 0.787234 (-6320 1835);
PAINT ORANGE (-6320 1835);
DISPLAY INVISIBLE (-6320 1835);
FORCEPROP 1 LASTPIN (-6325 2025) $PN 1
J 0
(-6320 1987);
DISPLAY 0.787234 (-6320 1987);
PAINT ORANGE (-6320 1987);
DISPLAY INVISIBLE (-6320 1987);
FORCEADD GND..1
(-3300 2100);
FORCEPROP 3 LASTPIN (-3300 2150) SIG_NAME GND\g
J 0
(-3290 2160);
DISPLAY 0.659574 (-3290 2160);
PAINT MONO (-3290 2160);
DISPLAY INVISIBLE (-3290 2160);
FORCEPROP 1 LAST HDL_POWER GND
J 0
(-3300 2250);
DISPLAY 0.872340 (-3300 2250);
PAINT GREEN (-3300 2250);
DISPLAY INVISIBLE (-3300 2250);
FORCEPROP 1 LAST SIZE 1B
J 0
(-3225 2050);
DISPLAY 0.872340 (-3225 2050);
PAINT AQUA (-3225 2050);
DISPLAY INVISIBLE (-3225 2050);
FORCEPROP 2 LAST CDS_LIB mstr_symbols
J 0
(-3300 2100);
PAINT MONO (-3300 2100);
DISPLAY INVISIBLE (-3300 2100);
FORCEPROP 1 LAST BODY_TYPE PLUMBING
J 0
(-3345 2057);
DISPLAY 0.340426 (-3345 2057);
PAINT GREEN (-3345 2057);
DISPLAY INVISIBLE (-3345 2057);
FORCEPROP 1 LAST VOLTAGE 0.0V
J 0
(-3345 2057);
DISPLAY 0.340426 (-3345 2057);
PAINT GREEN (-3345 2057);
DISPLAY INVISIBLE (-3345 2057);
FORCEPROP 1 LAST PATH I14
J 0
(-3225 2100);
DISPLAY 0.872340 (-3225 2100);
PAINT AQUA (-3225 2100);
DISPLAY INVISIBLE (-3225 2100);
FORCEADD LMV331IDCKRG4-GP..1
(-3250 2550);
FORCEPROP 1 LAST LOCATION Q9W4
J 0
(-3175 2660);
DISPLAY 0.617021 (-3175 2660);
PAINT GREEN (-3175 2660);
FORCEPROP 1 LAST VALUE LMV331IDCKRG4-GP
J 0
(-3175 2415);
DISPLAY 0.617021 (-3175 2415);
PAINT GREEN (-3175 2415);
FORCEPROP 1 LAST PATH I15
J 0
(-3250 2550);
DISPLAY 0.617021 (-3250 2550);
PAINT GREEN (-3250 2550);
DISPLAY INVISIBLE (-3250 2550);
FORCEPROP 1 LAST PACK_TYPE DISCRET-G
J 0
(-3250 2550);
DISPLAY 0.617021 (-3250 2550);
PAINT GREEN (-3250 2550);
DISPLAY INVISIBLE (-3250 2550);
FORCEPROP 1 LAST PART_NUMBER 74.00331.A2F
J 0
(-3250 2550);
DISPLAY 0.617021 (-3250 2550);
PAINT GREEN (-3250 2550);
DISPLAY INVISIBLE (-3250 2550);
FORCEPROP 2 LAST CDS_LIB w_hdl
J 0
(-3250 2550);
PAINT MONO (-3250 2550);
DISPLAY INVISIBLE (-3250 2550);
FORCEPROP 1 LAST CDS_LMAN_SYM_OUTLINE -100,100,100,-100
J 0
(-3250 2550);
DISPLAY 0.468085 (-3250 2550);
PAINT GREEN (-3250 2550);
DISPLAY INVISIBLE (-3250 2550);
FORCEADD P3V3_STBY..1
(-5875 3050);
FORCEPROP 3 LASTPIN (-5875 3000) SIG_NAME P3V3_STBY\g
J 0
(-5865 3010);
DISPLAY 0.659574 (-5865 3010);
PAINT MONO (-5865 3010);
DISPLAY INVISIBLE (-5865 3010);
FORCEPROP 2 LAST CDS_LIB mstr_symbols
J 0
(-5875 3050);
PAINT MONO (-5875 3050);
DISPLAY INVISIBLE (-5875 3050);
FORCEPROP 1 LAST SIZE 1B
J 0
(-5830 3072);
DISPLAY 0.340426 (-5830 3072);
PAINT GREEN (-5830 3072);
DISPLAY INVISIBLE (-5830 3072);
FORCEPROP 1 LAST BODY_TYPE PLUMBING
J 0
(-5920 3007);
DISPLAY 0.340426 (-5920 3007);
PAINT GREEN (-5920 3007);
DISPLAY INVISIBLE (-5920 3007);
FORCEPROP 1 LAST HDL_POWER P3V3_STBY
J 0
(-6175 2925);
DISPLAY 0.872340 (-6175 2925);
PAINT ORANGE (-6175 2925);
DISPLAY INVISIBLE (-6175 2925);
FORCEPROP 1 LAST VOLTAGE 3.3V
J 0
(-5920 3007);
DISPLAY 0.340426 (-5920 3007);
PAINT GREEN (-5920 3007);
DISPLAY INVISIBLE (-5920 3007);
FORCEPROP 1 LAST PATH I16
J 0
(-5830 3052);
DISPLAY 0.340426 (-5830 3052);
PAINT GREEN (-5830 3052);
DISPLAY INVISIBLE (-5830 3052);
FORCEADD RES..2
(-5875 2825);
FORCEPROP 1 LAST LOCATION R3W3
J 0
(-5830 2950);
DISPLAY 0.617021 (-5830 2950);
PAINT AQUA (-5830 2950);
FORCEPROP 1 LAST TOLERANCE 1%
J 0
(-5830 2850);
DISPLAY 0.617021 (-5830 2850);
PAINT SKYBLUE (-5830 2850);
FORCEPROP 1 LAST VALUE 10.0K
J 0
(-5830 2900);
DISPLAY 0.617021 (-5830 2900);
PAINT SKYBLUE (-5830 2900);
FORCEPROP 1 LAST PACK_TYPE 0402
J 0
(-5835 2650);
DISPLAY 0.617021 (-5835 2650);
PAINT SKYBLUE (-5835 2650);
FORCEPROP 1 LAST MATERIAL CHIP
J 0
(-5835 2750);
DISPLAY 0.617021 (-5835 2750);
PAINT SKYBLUE (-5835 2750);
FORCEPROP 1 LAST WATTAGE 1/16W
J 0
(-5835 2800);
DISPLAY 0.617021 (-5835 2800);
PAINT SKYBLUE (-5835 2800);
FORCEPROP 1 LAST PART_NUMBER G21796-016
J 0
(-5835 2700);
DISPLAY 0.617021 (-5835 2700);
PAINT BLUE (-5835 2700);
FORCEPROP 0 LAST BOM_COST ST_FLASH
J 0
(-5825 3150);
DISPLAY 1.021277 (-5825 3150);
PAINT ORANGE (-5825 3150);
DISPLAY INVISIBLE (-5825 3150);
FORCEPROP 0 LAST ROOM M_2
J 0
(-5825 3050);
DISPLAY 1.021277 (-5825 3050);
PAINT ORANGE (-5825 3050);
DISPLAY INVISIBLE (-5825 3050);
FORCEPROP 2 LAST CDS_LIB mstr_discrete
J 0
(-5875 2825);
PAINT MONO (-5875 2825);
DISPLAY INVISIBLE (-5875 2825);
FORCEPROP 1 LAST PATH I17
J 0
(-5825 3000);
DISPLAY 0.978723 (-5825 3000);
PAINT WHITE (-5825 3000);
DISPLAY INVISIBLE (-5825 3000);
FORCEPROP 1 LASTPIN (-5875 2725) $PN 2
J 0
(-5870 2735);
DISPLAY 0.787234 (-5870 2735);
PAINT ORANGE (-5870 2735);
DISPLAY INVISIBLE (-5870 2735);
FORCEPROP 1 LASTPIN (-5875 2925) $PN 1
J 0
(-5870 2887);
DISPLAY 0.787234 (-5870 2887);
PAINT ORANGE (-5870 2887);
DISPLAY INVISIBLE (-5870 2887);
FORCEADD GND..1
(-3950 3675);
FORCEPROP 3 LASTPIN (-3950 3725) SIG_NAME GND\g
J 0
(-3940 3735);
DISPLAY 0.659574 (-3940 3735);
PAINT MONO (-3940 3735);
DISPLAY INVISIBLE (-3940 3735);
FORCEPROP 2 LAST CDS_LIB mstr_symbols
J 0
(-3950 3675);
PAINT MONO (-3950 3675);
DISPLAY INVISIBLE (-3950 3675);
FORCEPROP 1 LAST SIZE 1B
J 0
(-3875 3625);
DISPLAY 0.872340 (-3875 3625);
PAINT AQUA (-3875 3625);
DISPLAY INVISIBLE (-3875 3625);
FORCEPROP 1 LAST HDL_POWER GND
J 0
(-3950 3825);
DISPLAY 0.872340 (-3950 3825);
PAINT GREEN (-3950 3825);
DISPLAY INVISIBLE (-3950 3825);
FORCEPROP 1 LAST BODY_TYPE PLUMBING
J 0
(-3995 3632);
DISPLAY 0.340426 (-3995 3632);
PAINT GREEN (-3995 3632);
DISPLAY INVISIBLE (-3995 3632);
FORCEPROP 1 LAST VOLTAGE 0.0V
J 0
(-3995 3632);
DISPLAY 0.340426 (-3995 3632);
PAINT GREEN (-3995 3632);
DISPLAY INVISIBLE (-3995 3632);
FORCEPROP 1 LAST PATH I18
J 0
(-3875 3675);
DISPLAY 0.872340 (-3875 3675);
PAINT AQUA (-3875 3675);
DISPLAY INVISIBLE (-3875 3675);
FORCEADD P3V3_STBY..1
(-2975 3150);
FORCEPROP 3 LASTPIN (-2975 3100) SIG_NAME P3V3_STBY\g
J 0
(-2965 3110);
DISPLAY 0.659574 (-2965 3110);
PAINT MONO (-2965 3110);
DISPLAY INVISIBLE (-2965 3110);
FORCEPROP 2 LAST CDS_LIB mstr_symbols
J 0
(-2975 3150);
PAINT MONO (-2975 3150);
DISPLAY INVISIBLE (-2975 3150);
FORCEPROP 1 LAST HDL_POWER P3V3_STBY
J 0
(-3275 3025);
DISPLAY 0.872340 (-3275 3025);
PAINT ORANGE (-3275 3025);
DISPLAY INVISIBLE (-3275 3025);
FORCEPROP 1 LAST BODY_TYPE PLUMBING
J 0
(-3020 3107);
DISPLAY 0.340426 (-3020 3107);
PAINT GREEN (-3020 3107);
DISPLAY INVISIBLE (-3020 3107);
FORCEPROP 1 LAST SIZE 1B
J 0
(-2930 3172);
DISPLAY 0.340426 (-2930 3172);
PAINT GREEN (-2930 3172);
DISPLAY INVISIBLE (-2930 3172);
FORCEPROP 1 LAST VOLTAGE 3.3V
J 0
(-3020 3107);
DISPLAY 0.340426 (-3020 3107);
PAINT GREEN (-3020 3107);
DISPLAY INVISIBLE (-3020 3107);
FORCEPROP 1 LAST PATH I19
J 0
(-2930 3152);
DISPLAY 0.340426 (-2930 3152);
PAINT GREEN (-2930 3152);
DISPLAY INVISIBLE (-2930 3152);
FORCEADD RES..2
(-6925 1950);
FORCEPROP 1 LAST PACK_TYPE 0402
J 0
(-6885 1775);
DISPLAY 0.617021 (-6885 1775);
PAINT SKYBLUE (-6885 1775);
FORCEPROP 1 LAST WATTAGE 1/16W
J 0
(-6885 1925);
DISPLAY 0.617021 (-6885 1925);
PAINT SKYBLUE (-6885 1925);
FORCEPROP 1 LAST MATERIAL CHIP
J 0
(-6885 1875);
DISPLAY 0.617021 (-6885 1875);
PAINT SKYBLUE (-6885 1875);
FORCEPROP 1 LAST TOLERANCE 1%
J 0
(-6880 1975);
DISPLAY 0.617021 (-6880 1975);
PAINT SKYBLUE (-6880 1975);
FORCEPROP 1 LAST PART_NUMBER G21796-026
J 0
(-6885 1825);
DISPLAY 0.617021 (-6885 1825);
PAINT BLUE (-6885 1825);
FORCEPROP 1 LAST VALUE 1.00K
J 0
(-6880 2025);
DISPLAY 0.617021 (-6880 2025);
PAINT SKYBLUE (-6880 2025);
FORCEPROP 1 LAST LOCATION R3W1
J 0
(-6880 2075);
DISPLAY 0.617021 (-6880 2075);
PAINT AQUA (-6880 2075);
FORCEPROP 0 LAST ROOM BMC_DEBUG_HEADER
J 0
(-6875 2175);
DISPLAY 1.021277 (-6875 2175);
PAINT ORANGE (-6875 2175);
DISPLAY INVISIBLE (-6875 2175);
FORCEPROP 2 LAST CDS_LIB mstr_discrete
J 0
(-6925 1950);
PAINT MONO (-6925 1950);
DISPLAY INVISIBLE (-6925 1950);
FORCEPROP 1 LAST PATH I2
J 0
(-6875 2125);
DISPLAY 0.978723 (-6875 2125);
PAINT WHITE (-6875 2125);
DISPLAY INVISIBLE (-6875 2125);
FORCEPROP 1 LASTPIN (-6925 1850) $PN 2
J 0
(-6920 1860);
DISPLAY 0.787234 (-6920 1860);
PAINT ORANGE (-6920 1860);
DISPLAY INVISIBLE (-6920 1860);
FORCEPROP 1 LASTPIN (-6925 2050) $PN 1
J 0
(-6920 2012);
DISPLAY 0.787234 (-6920 2012);
PAINT ORANGE (-6920 2012);
DISPLAY INVISIBLE (-6920 2012);
FORCEADD GND..1
(-2975 2750);
FORCEPROP 3 LASTPIN (-2975 2800) SIG_NAME GND\g
J 0
(-2965 2810);
DISPLAY 0.659574 (-2965 2810);
PAINT MONO (-2965 2810);
DISPLAY INVISIBLE (-2965 2810);
FORCEPROP 2 LAST CDS_LIB mstr_symbols
J 0
(-2975 2750);
PAINT MONO (-2975 2750);
DISPLAY INVISIBLE (-2975 2750);
FORCEPROP 1 LAST HDL_POWER GND
J 0
(-2975 2900);
DISPLAY 0.872340 (-2975 2900);
PAINT GREEN (-2975 2900);
DISPLAY INVISIBLE (-2975 2900);
FORCEPROP 1 LAST SIZE 1B
J 0
(-2900 2700);
DISPLAY 0.872340 (-2900 2700);
PAINT AQUA (-2900 2700);
DISPLAY INVISIBLE (-2900 2700);
FORCEPROP 1 LAST BODY_TYPE PLUMBING
J 0
(-3020 2707);
DISPLAY 0.340426 (-3020 2707);
PAINT GREEN (-3020 2707);
DISPLAY INVISIBLE (-3020 2707);
FORCEPROP 1 LAST VOLTAGE 0.0V
J 0
(-3020 2707);
DISPLAY 0.340426 (-3020 2707);
PAINT GREEN (-3020 2707);
DISPLAY INVISIBLE (-3020 2707);
FORCEPROP 1 LAST PATH I20
J 0
(-2900 2750);
DISPLAY 0.872340 (-2900 2750);
PAINT AQUA (-2900 2750);
DISPLAY INVISIBLE (-2900 2750);
FORCEADD CAP..1
(-2975 2950);
FORCEPROP 1 LAST LOCATION C8W2
J 0
(-2925 3050);
DISPLAY 0.617021 (-2925 3050);
PAINT AQUA (-2925 3050);
FORCEPROP 1 LAST MATERIAL X7R
J 0
(-2925 2850);
DISPLAY 0.617021 (-2925 2850);
PAINT SKYBLUE (-2925 2850);
FORCEPROP 1 LAST VOLTAGE 16V
J 0
(-2925 2950);
DISPLAY 0.617021 (-2925 2950);
PAINT SKYBLUE (-2925 2950);
FORCEPROP 1 LAST TOLERANCE 10%
J 0
(-2925 2900);
DISPLAY 0.617021 (-2925 2900);
PAINT SKYBLUE (-2925 2900);
FORCEPROP 1 LAST VALUE 0.1UF
J 0
(-2925 3000);
DISPLAY 0.617021 (-2925 3000);
PAINT SKYBLUE (-2925 3000);
FORCEPROP 1 LAST PART_NUMBER A36096-030
J 0
(-2925 2800);
DISPLAY 0.617021 (-2925 2800);
PAINT BLUE (-2925 2800);
FORCEPROP 1 LAST PACK_TYPE 0402LF
J 0
(-2925 2750);
DISPLAY 0.617021 (-2925 2750);
PAINT SKYBLUE (-2925 2750);
FORCEPROP 2 LAST CDS_LIB mstr_discrete
J 0
(-2975 2950);
PAINT MONO (-2975 2950);
DISPLAY INVISIBLE (-2975 2950);
FORCEPROP 0 LAST ROOM M_2
J 0
(-2925 3150);
DISPLAY 1.021277 (-2925 3150);
PAINT ORANGE (-2925 3150);
DISPLAY INVISIBLE (-2925 3150);
FORCEPROP 0 LAST BOM_COST SD_FLASH
J 0
(-2925 3250);
DISPLAY 1.021277 (-2925 3250);
PAINT ORANGE (-2925 3250);
DISPLAY INVISIBLE (-2925 3250);
FORCEPROP 1 LAST PATH I21
J 0
(-2925 3100);
DISPLAY 0.978723 (-2925 3100);
PAINT WHITE (-2925 3100);
DISPLAY INVISIBLE (-2925 3100);
FORCEPROP 1 LASTPIN (-2975 2850) $PN 2
J 0
(-2965 2830);
DISPLAY 0.787234 (-2965 2830);
PAINT ORANGE (-2965 2830);
DISPLAY INVISIBLE (-2965 2830);
FORCEPROP 1 LASTPIN (-2975 3050) $PN 1
J 0
(-2965 3030);
DISPLAY 0.787234 (-2965 3030);
PAINT ORANGE (-2965 3030);
DISPLAY INVISIBLE (-2965 3030);
FORCEADD OFFPAGE..2
(-2400 2550);
FORCEPROP 2 LAST $XR0 133 
J 0
(-2211 2550);
DISPLAY 0.638298 (-2211 2550);
PAINT MONO (-2211 2550);
FORCEPROP 2 LAST $XR1 119 
J 0
(-2091 2550);
DISPLAY 0.638298 (-2091 2550);
PAINT MONO (-2091 2550);
FORCEPROP 2 LAST $XR2 147 
J 0
(-1971 2550);
DISPLAY 0.638298 (-1971 2550);
PAINT MONO (-1971 2550);
FORCEPROP 2 LAST CDS_LIB mstr_standard
J 0
(-2400 2550);
PAINT MONO (-2400 2550);
DISPLAY INVISIBLE (-2400 2550);
FORCEPROP 1 LAST COMMENT_BODY TRUE
J 0
(-2445 2455);
DISPLAY 0.872340 (-2445 2455);
PAINT GREEN (-2445 2455);
DISPLAY INVISIBLE (-2445 2455);
FORCEPROP 1 LAST OFFPAGE TRUE
J 0
(-2075 2425);
DISPLAY 0.872340 (-2075 2425);
PAINT GREEN (-2075 2425);
DISPLAY INVISIBLE (-2075 2425);
FORCEPROP 2 LAST PATH I22
J 0
(-2225 2625);
DISPLAY 1.021277 (-2225 2625);
PAINT ORANGE (-2225 2625);
DISPLAY INVISIBLE (-2225 2625);
FORCEADD P3V3_STBY..1
(-4550 4725);
FORCEPROP 3 LASTPIN (-4550 4675) SIG_NAME P3V3_STBY\g
J 0
(-4540 4685);
DISPLAY 0.659574 (-4540 4685);
PAINT MONO (-4540 4685);
DISPLAY INVISIBLE (-4540 4685);
FORCEPROP 1 LAST HDL_POWER P3V3_STBY
J 0
(-4850 4600);
DISPLAY 0.872340 (-4850 4600);
PAINT ORANGE (-4850 4600);
DISPLAY INVISIBLE (-4850 4600);
FORCEPROP 1 LAST BODY_TYPE PLUMBING
J 0
(-4595 4682);
DISPLAY 0.340426 (-4595 4682);
PAINT GREEN (-4595 4682);
DISPLAY INVISIBLE (-4595 4682);
FORCEPROP 1 LAST SIZE 1B
J 0
(-4505 4747);
DISPLAY 0.340426 (-4505 4747);
PAINT GREEN (-4505 4747);
DISPLAY INVISIBLE (-4505 4747);
FORCEPROP 2 LAST CDS_LIB mstr_symbols
J 0
(-4550 4725);
PAINT MONO (-4550 4725);
DISPLAY INVISIBLE (-4550 4725);
FORCEPROP 1 LAST VOLTAGE 3.3V
J 0
(-4595 4682);
DISPLAY 0.340426 (-4595 4682);
PAINT GREEN (-4595 4682);
DISPLAY INVISIBLE (-4595 4682);
FORCEPROP 1 LAST PATH I24
J 0
(-4505 4727);
DISPLAY 0.340426 (-4505 4727);
PAINT GREEN (-4505 4727);
DISPLAY INVISIBLE (-4505 4727);
FORCEADD NPN..1
(-4000 4125);
FORCEPROP 1 LAST PART_NUMBER C52245-001
J 0
(-3850 3975);
DISPLAY 0.617021 (-3850 3975);
PAINT BLUE (-3850 3975);
FORCEPROP 1 LAST MATERIAL IC
J 0
(-3850 4075);
DISPLAY 0.617021 (-3850 4075);
PAINT SKYBLUE (-3850 4075);
FORCEPROP 1 LAST VALUE MMBT3904
J 0
(-3850 4125);
DISPLAY 0.617021 (-3850 4125);
PAINT SKYBLUE (-3850 4125);
FORCEPROP 1 LAST PACK_TYPE SM
J 0
(-3850 4025);
DISPLAY 0.617021 (-3850 4025);
PAINT SKYBLUE (-3850 4025);
FORCEPROP 1 LAST LOCATION Q9W3
J 0
(-3850 4175);
DISPLAY 0.617021 (-3850 4175);
PAINT AQUA (-3850 4175);
FORCEPROP 2 LAST CDS_LIB mstr_discrete
J 0
(-4000 4125);
PAINT MONO (-4000 4125);
DISPLAY INVISIBLE (-4000 4125);
FORCEPROP 2 LAST ROOM SB
J 0
(-3850 4225);
DISPLAY 1.404255 (-3850 4225);
PAINT ORANGE (-3850 4225);
DISPLAY INVISIBLE (-3850 4225);
FORCEPROP 1 LAST PATH I26
J 0
(-3850 4225);
DISPLAY 0.978723 (-3850 4225);
PAINT BLUE (-3850 4225);
DISPLAY INVISIBLE (-3850 4225);
FORCEPROP 1 LASTPIN (-4100 4125) $PN 1
J 0
(-4155 4150);
DISPLAY 0.957447 (-4155 4150);
PAINT GREEN (-4155 4150);
DISPLAY INVISIBLE (-4155 4150);
FORCEPROP 1 LASTPIN (-3950 4025) $PN 2
J 0
(-3925 3975);
DISPLAY 0.957447 (-3925 3975);
PAINT GREEN (-3925 3975);
DISPLAY INVISIBLE (-3925 3975);
FORCEPROP 1 LASTPIN (-3950 4225) $PN 3
J 0
(-3931 4235);
DISPLAY 0.957447 (-3931 4235);
PAINT GREEN (-3931 4235);
DISPLAY INVISIBLE (-3931 4235);
FORCEADD RES..2
R 2
(-3950 4425);
FORCEPROP 1 LAST PART_NUMBER G21796-072
J 2
(-3990 4300);
DISPLAY 0.617021 (-3990 4300);
PAINT BLUE (-3990 4300);
FORCEPROP 1 LAST TOLERANCE 1%
J 2
(-3995 4400);
DISPLAY 0.617021 (-3995 4400);
PAINT SKYBLUE (-3995 4400);
FORCEPROP 1 LAST PACK_TYPE 0402
J 2
(-3990 4250);
DISPLAY 0.617021 (-3990 4250);
PAINT SKYBLUE (-3990 4250);
FORCEPROP 1 LAST WATTAGE 1/16W
J 2
(-3990 4350);
DISPLAY 0.617021 (-3990 4350);
PAINT SKYBLUE (-3990 4350);
FORCEPROP 1 LAST MATERIAL CHIP
J 2
(-3990 4450);
DISPLAY 0.617021 (-3990 4450);
PAINT SKYBLUE (-3990 4450);
FORCEPROP 1 LAST VALUE 4.75K
J 2
(-3995 4500);
DISPLAY 0.617021 (-3995 4500);
PAINT SKYBLUE (-3995 4500);
FORCEPROP 1 LAST LOCATION R3W6
J 2
(-3995 4550);
DISPLAY 0.617021 (-3995 4550);
PAINT AQUA (-3995 4550);
FORCEPROP 1 LASTPIN (-3950 4525) $PN 1
J 2
(-3955 4487);
DISPLAY 0.787234 (-3955 4487);
PAINT ORANGE (-3955 4487);
DISPLAY INVISIBLE (-3955 4487);
FORCEPROP 1 LASTPIN (-3950 4325) $PN 2
J 2
(-3955 4335);
DISPLAY 0.787234 (-3955 4335);
PAINT ORANGE (-3955 4335);
DISPLAY INVISIBLE (-3955 4335);
FORCEPROP 1 LAST PATH I27
J 2
(-4000 4600);
DISPLAY 0.978723 (-4000 4600);
PAINT WHITE (-4000 4600);
DISPLAY INVISIBLE (-4000 4600);
FORCEPROP 2 LAST NO_XNET_CONNECTION 1
J 0
(-4000 4650);
PAINT MONO (-4000 4650);
DISPLAY INVISIBLE (-4000 4650);
FORCEPROP 2 LAST BOM_COST MIO_BIOS_MEM
J 0
(-3975 4650);
DISPLAY 1.021277 (-3975 4650);
PAINT ORANGE (-3975 4650);
DISPLAY INVISIBLE (-3975 4650);
FORCEPROP 2 LAST ROOM SB_SPI
J 0
(-3975 4600);
DISPLAY 1.021277 (-3975 4600);
PAINT ORANGE (-3975 4600);
DISPLAY INVISIBLE (-3975 4600);
FORCEPROP 2 LAST CDS_LIB mstr_discrete
J 0
(-3950 4425);
PAINT MONO (-3950 4425);
DISPLAY INVISIBLE (-3950 4425);
FORCEADD OFFPAGE..2
(-2975 4325);
FORCEPROP 2 LAST $XR3 ?
J 0
(-2426 4325);
DISPLAY 0.638298 (-2426 4325);
PAINT MONO (-2426 4325);
FORCEPROP 2 LAST $XR2 145 
J 0
(-2546 4325);
DISPLAY 0.638298 (-2546 4325);
PAINT MONO (-2546 4325);
FORCEPROP 2 LAST $XR1 135 
J 0
(-2666 4325);
DISPLAY 0.638298 (-2666 4325);
PAINT MONO (-2666 4325);
FORCEPROP 2 LAST $XR0 118 
J 0
(-2786 4325);
DISPLAY 0.638298 (-2786 4325);
PAINT MONO (-2786 4325);
FORCEPROP 2 LAST PATH I28
J 0
(-2800 4400);
DISPLAY 1.021277 (-2800 4400);
PAINT ORANGE (-2800 4400);
DISPLAY INVISIBLE (-2800 4400);
FORCEPROP 1 LAST COMMENT_BODY TRUE
J 0
(-3020 4230);
DISPLAY 0.872340 (-3020 4230);
PAINT GREEN (-3020 4230);
DISPLAY INVISIBLE (-3020 4230);
FORCEPROP 1 LAST OFFPAGE TRUE
J 0
(-2650 4200);
DISPLAY 0.872340 (-2650 4200);
PAINT GREEN (-2650 4200);
DISPLAY INVISIBLE (-2650 4200);
FORCEPROP 2 LAST CDS_LIB mstr_standard
J 0
(-2975 4325);
PAINT MONO (-2975 4325);
DISPLAY INVISIBLE (-2975 4325);
FORCEADD NPN..1
(-4600 3975);
FORCEPROP 1 LAST LOCATION Q9W2
J 0
(-4450 4025);
DISPLAY 0.617021 (-4450 4025);
PAINT AQUA (-4450 4025);
FORCEPROP 1 LAST PACK_TYPE SM
J 0
(-4450 3875);
DISPLAY 0.617021 (-4450 3875);
PAINT SKYBLUE (-4450 3875);
FORCEPROP 1 LAST MATERIAL IC
J 0
(-4450 3925);
DISPLAY 0.617021 (-4450 3925);
PAINT SKYBLUE (-4450 3925);
FORCEPROP 1 LAST PART_NUMBER C52245-001
J 0
(-4450 3825);
DISPLAY 0.617021 (-4450 3825);
PAINT BLUE (-4450 3825);
FORCEPROP 1 LAST VALUE MMBT3904
J 0
(-4450 3975);
DISPLAY 0.617021 (-4450 3975);
PAINT SKYBLUE (-4450 3975);
FORCEPROP 2 LAST ROOM SB
J 0
(-4450 4075);
DISPLAY 1.404255 (-4450 4075);
PAINT ORANGE (-4450 4075);
DISPLAY INVISIBLE (-4450 4075);
FORCEPROP 2 LAST CDS_LIB mstr_discrete
J 0
(-4600 3975);
PAINT MONO (-4600 3975);
DISPLAY INVISIBLE (-4600 3975);
FORCEPROP 1 LAST PATH I29
J 0
(-4450 4075);
DISPLAY 0.978723 (-4450 4075);
PAINT BLUE (-4450 4075);
DISPLAY INVISIBLE (-4450 4075);
FORCEPROP 1 LASTPIN (-4700 3975) $PN 1
J 0
(-4755 4000);
DISPLAY 0.957447 (-4755 4000);
PAINT GREEN (-4755 4000);
DISPLAY INVISIBLE (-4755 4000);
FORCEPROP 1 LASTPIN (-4550 3875) $PN 2
J 0
(-4525 3825);
DISPLAY 0.957447 (-4525 3825);
PAINT GREEN (-4525 3825);
DISPLAY INVISIBLE (-4525 3825);
FORCEPROP 1 LASTPIN (-4550 4075) $PN 3
J 0
(-4531 4085);
DISPLAY 0.957447 (-4531 4085);
PAINT GREEN (-4531 4085);
DISPLAY INVISIBLE (-4531 4085);
FORCEADD GND..1
(-6925 1625);
FORCEPROP 3 LASTPIN (-6925 1675) SIG_NAME GND\g
J 0
(-6915 1685);
DISPLAY 0.659574 (-6915 1685);
PAINT MONO (-6915 1685);
DISPLAY INVISIBLE (-6915 1685);
FORCEPROP 1 LAST HDL_POWER GND
J 0
(-6925 1775);
DISPLAY 0.872340 (-6925 1775);
PAINT GREEN (-6925 1775);
DISPLAY INVISIBLE (-6925 1775);
FORCEPROP 1 LAST SIZE 1B
J 0
(-6850 1575);
DISPLAY 0.872340 (-6850 1575);
PAINT AQUA (-6850 1575);
DISPLAY INVISIBLE (-6850 1575);
FORCEPROP 2 LAST CDS_LIB mstr_symbols
J 0
(-6925 1625);
PAINT MONO (-6925 1625);
DISPLAY INVISIBLE (-6925 1625);
FORCEPROP 1 LAST BODY_TYPE PLUMBING
J 0
(-6970 1582);
DISPLAY 0.340426 (-6970 1582);
PAINT GREEN (-6970 1582);
DISPLAY INVISIBLE (-6970 1582);
FORCEPROP 1 LAST VOLTAGE 0.0V
J 0
(-6970 1582);
DISPLAY 0.340426 (-6970 1582);
PAINT GREEN (-6970 1582);
DISPLAY INVISIBLE (-6970 1582);
FORCEPROP 1 LAST PATH I3
J 0
(-6850 1625);
DISPLAY 0.872340 (-6850 1625);
PAINT AQUA (-6850 1625);
DISPLAY INVISIBLE (-6850 1625);
FORCEADD FET_N..8
(-5875 2250);
FORCEPROP 1 LAST PART_NUMBER C79254-001
J 0
(-5675 2050);
DISPLAY 0.617021 (-5675 2050);
PAINT BLUE (-5675 2050);
FORCEPROP 1 LAST LOCATION Q9W1
J 0
(-5675 2250);
DISPLAY 0.617021 (-5675 2250);
PAINT AQUA (-5675 2250);
FORCEPROP 1 LAST MATERIAL FET
J 0
(-5675 2150);
DISPLAY 0.617021 (-5675 2150);
PAINT SKYBLUE (-5675 2150);
FORCEPROP 1 LAST VALUE 2N7002
J 0
(-5675 2200);
DISPLAY 0.617021 (-5675 2200);
PAINT SKYBLUE (-5675 2200);
FORCEPROP 2 LAST CDS_LIB mstr_discrete
J 0
(-5875 2250);
PAINT MONO (-5875 2250);
DISPLAY INVISIBLE (-5875 2250);
FORCEPROP 1 LAST PATH I30
J 0
(-5675 2300);
DISPLAY 0.978723 (-5675 2300);
PAINT BLUE (-5675 2300);
DISPLAY INVISIBLE (-5675 2300);
FORCEPROP 1 LAST PACK_TYPE SOT23LF
J 0
(-5675 2100);
DISPLAY 0.978723 (-5675 2100);
PAINT SKYBLUE (-5675 2100);
DISPLAY INVISIBLE (-5675 2100);
FORCEPROP 0 LAST ROOM HOT_SWAP
J 0
(-5675 2350);
DISPLAY 1.021277 (-5675 2350);
PAINT ORANGE (-5675 2350);
DISPLAY INVISIBLE (-5675 2350);
FORCEPROP 1 LASTPIN (-5875 2050) $PN 2
J 2
(-5817 2050);
DISPLAY 0.872340 (-5817 2050);
PAINT WHITE (-5817 2050);
DISPLAY INVISIBLE (-5817 2050);
FORCEPROP 1 LASTPIN (-5875 2450) $PN 3
J 2
(-5822 2415);
DISPLAY 0.872340 (-5822 2415);
PAINT WHITE (-5822 2415);
DISPLAY INVISIBLE (-5822 2415);
FORCEPROP 1 LASTPIN (-6075 2150) $PN 1
J 2
(-6072 2165);
DISPLAY 0.872340 (-6072 2165);
PAINT WHITE (-6072 2165);
DISPLAY INVISIBLE (-6072 2165);
FORCEADD 47KR2F-GP..1
R 1
(-5375 3975);
FORCEPROP 1 LAST VALUE 47KR2F-GP
J 0
(-5425 3875);
DISPLAY 0.617021 (-5425 3875);
PAINT GREEN (-5425 3875);
FORCEPROP 1 LAST LOCATION R3W4
J 0
(-5425 3900);
DISPLAY 0.617021 (-5425 3900);
PAINT GREEN (-5425 3900);
FORCEPROP 1 LAST CDS_LMAN_SYM_OUTLINE -50,75,50,-75
R 1
J 0
(-5375 3975);
DISPLAY 0.468085 (-5375 3975);
PAINT GREEN (-5375 3975);
DISPLAY INVISIBLE (-5375 3975);
FORCEPROP 1 LAST PATH I31
R 1
J 0
(-5375 3975);
DISPLAY 0.617021 (-5375 3975);
PAINT GREEN (-5375 3975);
DISPLAY INVISIBLE (-5375 3975);
FORCEPROP 2 LAST CDS_LIB w_hdl
R 1
J 0
(-5375 3975);
PAINT MONO (-5375 3975);
DISPLAY INVISIBLE (-5375 3975);
FORCEPROP 1 LAST PART_NUMBER 64.47025.6DL
R 1
J 0
(-5375 3975);
DISPLAY 0.617021 (-5375 3975);
PAINT GREEN (-5375 3975);
DISPLAY INVISIBLE (-5375 3975);
FORCEPROP 1 LAST PACK_TYPE RCL_GP
R 1
J 0
(-5375 3975);
DISPLAY 0.617021 (-5375 3975);
PAINT GREEN (-5375 3975);
DISPLAY INVISIBLE (-5375 3975);
FORCEADD CAP..1
R 1
(-6800 2150);
FORCEPROP 1 LAST LOCATION C8W1
R 1
J 0
(-6900 2200);
DISPLAY 0.617021 (-6900 2200);
PAINT AQUA (-6900 2200);
FORCEPROP 1 LAST VOLTAGE 6.3V
R 1
J 0
(-6800 2200);
DISPLAY 0.617021 (-6800 2200);
PAINT SKYBLUE (-6800 2200);
FORCEPROP 1 LAST TOLERANCE 20%
R 1
J 0
(-6750 2200);
DISPLAY 0.617021 (-6750 2200);
PAINT SKYBLUE (-6750 2200);
FORCEPROP 1 LAST PACK_TYPE 0603
R 1
J 0
(-6600 2200);
DISPLAY 0.617021 (-6600 2200);
PAINT SKYBLUE (-6600 2200);
FORCEPROP 1 LAST PART_NUMBER E15431-002
R 1
J 0
(-6650 2200);
DISPLAY 0.617021 (-6650 2200);
PAINT BLUE (-6650 2200);
FORCEPROP 1 LAST MATERIAL X6S
R 1
J 0
(-6700 2200);
DISPLAY 0.617021 (-6700 2200);
PAINT SKYBLUE (-6700 2200);
FORCEPROP 1 LAST VALUE 10UF
R 1
J 0
(-6850 2200);
DISPLAY 0.617021 (-6850 2200);
PAINT SKYBLUE (-6850 2200);
FORCEPROP 2 LAST CDS_LIB mstr_discrete
R 1
J 0
(-6800 2150);
PAINT MONO (-6800 2150);
DISPLAY INVISIBLE (-6800 2150);
FORCEPROP 1 LAST PATH I32
R 1
J 0
(-6950 2200);
DISPLAY 0.978723 (-6950 2200);
PAINT WHITE (-6950 2200);
DISPLAY INVISIBLE (-6950 2200);
FORCEPROP 2 LAST BOM_COST NT_GBE_BASE
R 1
J 0
(-7000 2200);
DISPLAY 1.021277 (-7000 2200);
PAINT ORANGE (-7000 2200);
DISPLAY INVISIBLE (-7000 2200);
FORCEPROP 2 LAST ROOM NIC_SPRV
R 1
J 0
(-6950 2200);
DISPLAY 1.021277 (-6950 2200);
PAINT ORANGE (-6950 2200);
DISPLAY INVISIBLE (-6950 2200);
FORCEPROP 1 LASTPIN (-6700 2150) $PN 2
R 1
J 0
(-6680 2160);
DISPLAY 0.787234 (-6680 2160);
PAINT ORANGE (-6680 2160);
DISPLAY INVISIBLE (-6680 2160);
FORCEPROP 1 LASTPIN (-6900 2150) $PN 1
R 1
J 0
(-6880 2160);
DISPLAY 0.787234 (-6880 2160);
PAINT ORANGE (-6880 2160);
DISPLAY INVISIBLE (-6880 2160);
FORCEADD 82K5R2F-GP..1
(-4550 4400);
FORCEPROP 1 LAST LOCATION R3W5
J 0
(-4525 4500);
DISPLAY 0.617021 (-4525 4500);
PAINT GREEN (-4525 4500);
FORCEPROP 1 LAST VALUE 82K5R2F-GP
J 0
(-4525 4275);
DISPLAY 0.617021 (-4525 4275);
PAINT GREEN (-4525 4275);
FORCEPROP 1 LAST PACK_TYPE SMD-RG
J 0
(-4550 4400);
DISPLAY 0.617021 (-4550 4400);
PAINT GREEN (-4550 4400);
DISPLAY INVISIBLE (-4550 4400);
FORCEPROP 1 LAST PART_NUMBER 64.82525.6DL
J 0
(-4550 4400);
DISPLAY 0.617021 (-4550 4400);
PAINT GREEN (-4550 4400);
DISPLAY INVISIBLE (-4550 4400);
FORCEPROP 2 LAST CDS_LIB w_hdl
J 0
(-4550 4400);
PAINT MONO (-4550 4400);
DISPLAY INVISIBLE (-4550 4400);
FORCEPROP 1 LAST PATH I33
J 0
(-4550 4400);
DISPLAY 0.617021 (-4550 4400);
PAINT GREEN (-4550 4400);
DISPLAY INVISIBLE (-4550 4400);
FORCEPROP 1 LAST CDS_LMAN_SYM_OUTLINE -50,75,50,-75
J 0
(-4550 4400);
DISPLAY 0.468085 (-4550 4400);
PAINT GREEN (-4550 4400);
DISPLAY INVISIBLE (-4550 4400);
FORCEADD OFFPAGE..1
(-6150 3975);
FORCEPROP 2 LAST $XR0 157 
J 0
(-6477 3975);
DISPLAY 0.638298 (-6477 3975);
PAINT MONO (-6477 3975);
FORCEPROP 2 LAST $XR1 184 
J 0
(-6402 3975);
DISPLAY 0.638298 (-6402 3975);
PAINT MONO (-6402 3975);
FORCEPROP 2 LAST CDS_LIB mstr_standard
J 0
(-6150 3975);
PAINT MONO (-6150 3975);
DISPLAY INVISIBLE (-6150 3975);
FORCEPROP 1 LAST OFFPAGE TRUE
J 0
(-5825 3850);
DISPLAY 0.872340 (-5825 3850);
PAINT GREEN (-5825 3850);
DISPLAY INVISIBLE (-5825 3850);
FORCEPROP 1 LAST COMMENT_BODY TRUE
J 0
(-6025 3875);
DISPLAY 0.872340 (-6025 3875);
PAINT GREEN (-6025 3875);
DISPLAY INVISIBLE (-6025 3875);
FORCEPROP 2 LAST PATH I5
J 0
(-6100 4050);
DISPLAY 1.021277 (-6100 4050);
PAINT ORANGE (-6100 4050);
DISPLAY INVISIBLE (-6100 4050);
FORCEADD GND..1
(-4225 1975);
FORCEPROP 3 LASTPIN (-4225 2025) SIG_NAME GND\g
J 0
(-4215 2035);
DISPLAY 0.659574 (-4215 2035);
PAINT MONO (-4215 2035);
DISPLAY INVISIBLE (-4215 2035);
FORCEPROP 2 LAST CDS_LIB mstr_symbols
J 0
(-4225 1975);
PAINT MONO (-4225 1975);
DISPLAY INVISIBLE (-4225 1975);
FORCEPROP 1 LAST HDL_POWER GND
J 0
(-4225 2125);
DISPLAY 0.872340 (-4225 2125);
PAINT GREEN (-4225 2125);
DISPLAY INVISIBLE (-4225 2125);
FORCEPROP 1 LAST SIZE 1B
J 0
(-4150 1925);
DISPLAY 0.872340 (-4150 1925);
PAINT AQUA (-4150 1925);
DISPLAY INVISIBLE (-4150 1925);
FORCEPROP 1 LAST BODY_TYPE PLUMBING
J 0
(-4270 1932);
DISPLAY 0.340426 (-4270 1932);
PAINT GREEN (-4270 1932);
DISPLAY INVISIBLE (-4270 1932);
FORCEPROP 1 LAST VOLTAGE 0.0V
J 0
(-4270 1932);
DISPLAY 0.340426 (-4270 1932);
PAINT GREEN (-4270 1932);
DISPLAY INVISIBLE (-4270 1932);
FORCEPROP 1 LAST PATH I6
J 0
(-4150 1975);
DISPLAY 0.872340 (-4150 1975);
PAINT AQUA (-4150 1975);
DISPLAY INVISIBLE (-4150 1975);
FORCEADD RES..2
(-4225 2300);
FORCEPROP 1 LAST LOCATION R3W9
J 0
(-4180 2425);
DISPLAY 0.617021 (-4180 2425);
PAINT AQUA (-4180 2425);
FORCEPROP 1 LAST VALUE 10.0K
J 0
(-4180 2375);
DISPLAY 0.617021 (-4180 2375);
PAINT SKYBLUE (-4180 2375);
FORCEPROP 1 LAST TOLERANCE 1%
J 0
(-4180 2325);
DISPLAY 0.617021 (-4180 2325);
PAINT SKYBLUE (-4180 2325);
FORCEPROP 1 LAST WATTAGE 1/16W
J 0
(-4185 2275);
DISPLAY 0.617021 (-4185 2275);
PAINT SKYBLUE (-4185 2275);
FORCEPROP 1 LAST PART_NUMBER G21796-016
J 0
(-4185 2175);
DISPLAY 0.617021 (-4185 2175);
PAINT BLUE (-4185 2175);
FORCEPROP 1 LAST MATERIAL CHIP
J 0
(-4185 2225);
DISPLAY 0.617021 (-4185 2225);
PAINT SKYBLUE (-4185 2225);
FORCEPROP 1 LAST PACK_TYPE 0402
J 0
(-4185 2125);
DISPLAY 0.617021 (-4185 2125);
PAINT SKYBLUE (-4185 2125);
FORCEPROP 2 LAST CDS_LIB mstr_discrete
J 0
(-4225 2300);
PAINT MONO (-4225 2300);
DISPLAY INVISIBLE (-4225 2300);
FORCEPROP 0 LAST BOM_COST ST_FLASH
J 0
(-4175 2625);
DISPLAY 1.021277 (-4175 2625);
PAINT ORANGE (-4175 2625);
DISPLAY INVISIBLE (-4175 2625);
FORCEPROP 0 LAST ROOM M_2
J 0
(-4175 2525);
DISPLAY 1.021277 (-4175 2525);
PAINT ORANGE (-4175 2525);
DISPLAY INVISIBLE (-4175 2525);
FORCEPROP 1 LAST PATH I7
J 0
(-4175 2475);
DISPLAY 0.978723 (-4175 2475);
PAINT WHITE (-4175 2475);
DISPLAY INVISIBLE (-4175 2475);
FORCEPROP 1 LASTPIN (-4225 2200) $PN 2
J 0
(-4220 2210);
DISPLAY 0.787234 (-4220 2210);
PAINT ORANGE (-4220 2210);
DISPLAY INVISIBLE (-4220 2210);
FORCEPROP 1 LASTPIN (-4225 2400) $PN 1
J 0
(-4220 2362);
DISPLAY 0.787234 (-4220 2362);
PAINT ORANGE (-4220 2362);
DISPLAY INVISIBLE (-4220 2362);
FORCEADD RES..2
R 2
(-4225 2775);
FORCEPROP 1 LAST LOCATION R3W7
J 2
(-4270 2900);
DISPLAY 0.617021 (-4270 2900);
PAINT AQUA (-4270 2900);
FORCEPROP 1 LAST MATERIAL CHIP
J 2
(-4265 2800);
DISPLAY 0.617021 (-4265 2800);
PAINT SKYBLUE (-4265 2800);
FORCEPROP 1 LAST TOLERANCE 1%
J 2
(-4270 2750);
DISPLAY 0.617021 (-4270 2750);
PAINT SKYBLUE (-4270 2750);
FORCEPROP 1 LAST VALUE 4.75K
J 2
(-4270 2850);
DISPLAY 0.617021 (-4270 2850);
PAINT SKYBLUE (-4270 2850);
FORCEPROP 1 LAST PACK_TYPE 0402
J 2
(-4265 2600);
DISPLAY 0.617021 (-4265 2600);
PAINT SKYBLUE (-4265 2600);
FORCEPROP 1 LAST WATTAGE 1/16W
J 2
(-4265 2700);
DISPLAY 0.617021 (-4265 2700);
PAINT SKYBLUE (-4265 2700);
FORCEPROP 1 LAST PART_NUMBER G21796-072
J 2
(-4265 2650);
DISPLAY 0.617021 (-4265 2650);
PAINT BLUE (-4265 2650);
FORCEPROP 2 LAST ROOM SB_SPI
J 0
(-4250 2950);
DISPLAY 1.021277 (-4250 2950);
PAINT ORANGE (-4250 2950);
DISPLAY INVISIBLE (-4250 2950);
FORCEPROP 2 LAST BOM_COST MIO_BIOS_MEM
J 0
(-4250 3000);
DISPLAY 1.021277 (-4250 3000);
PAINT ORANGE (-4250 3000);
DISPLAY INVISIBLE (-4250 3000);
FORCEPROP 2 LAST NO_XNET_CONNECTION 1
J 0
(-4275 3000);
PAINT MONO (-4275 3000);
DISPLAY INVISIBLE (-4275 3000);
FORCEPROP 2 LAST CDS_LIB mstr_discrete
J 0
(-4225 2775);
PAINT MONO (-4225 2775);
DISPLAY INVISIBLE (-4225 2775);
FORCEPROP 1 LAST PATH I8
J 2
(-4275 2950);
DISPLAY 0.978723 (-4275 2950);
PAINT WHITE (-4275 2950);
DISPLAY INVISIBLE (-4275 2950);
FORCEPROP 1 LASTPIN (-4225 2675) $PN 2
J 2
(-4230 2685);
DISPLAY 0.787234 (-4230 2685);
PAINT ORANGE (-4230 2685);
DISPLAY INVISIBLE (-4230 2685);
FORCEPROP 1 LASTPIN (-4225 2875) $PN 1
J 2
(-4230 2837);
DISPLAY 0.787234 (-4230 2837);
PAINT ORANGE (-4230 2837);
DISPLAY INVISIBLE (-4230 2837);
FORCEADD P3V3_STBY..1
(-4225 3100);
FORCEPROP 3 LASTPIN (-4225 3050) SIG_NAME P3V3_STBY\g
J 0
(-4215 3060);
DISPLAY 0.659574 (-4215 3060);
PAINT MONO (-4215 3060);
DISPLAY INVISIBLE (-4215 3060);
FORCEPROP 1 LAST HDL_POWER P3V3_STBY
J 0
(-4525 2975);
DISPLAY 0.872340 (-4525 2975);
PAINT ORANGE (-4525 2975);
DISPLAY INVISIBLE (-4525 2975);
FORCEPROP 1 LAST BODY_TYPE PLUMBING
J 0
(-4270 3057);
DISPLAY 0.340426 (-4270 3057);
PAINT GREEN (-4270 3057);
DISPLAY INVISIBLE (-4270 3057);
FORCEPROP 1 LAST SIZE 1B
J 0
(-4180 3122);
DISPLAY 0.340426 (-4180 3122);
PAINT GREEN (-4180 3122);
DISPLAY INVISIBLE (-4180 3122);
FORCEPROP 2 LAST CDS_LIB mstr_symbols
J 0
(-4225 3100);
PAINT MONO (-4225 3100);
DISPLAY INVISIBLE (-4225 3100);
FORCEPROP 1 LAST VOLTAGE 3.3V
J 0
(-4270 3057);
DISPLAY 0.340426 (-4270 3057);
PAINT GREEN (-4270 3057);
DISPLAY INVISIBLE (-4270 3057);
FORCEPROP 1 LAST PATH I9
J 0
(-4180 3102);
DISPLAY 0.340426 (-4180 3102);
PAINT GREEN (-4180 3102);
DISPLAY INVISIBLE (-4180 3102);
FORCEADD INTEL_CORP_BPAGE..1
(0 0);
FORCEPROP 1 LAST CDS_CON_LAST_MODIFIED Tue Dec 01 11:52:33 2015
J 0
(-1425 325);
PAINT ORANGE (-1425 325);
DISPLAY INVISIBLE (-1425 325);
FORCEPROP 2 LAST CUSTOM_TXT_CDS <XR_PAGE_TITLE>
J 0
(-7890 5250);
DISPLAY 0.638298 (-7890 5250);
PAINT PINK (-7890 5250);
DISPLAY INVISIBLE (-7890 5250);
FORCEPROP 2 LAST CUSTOM_TXT_CDS <CURRENT_DESIGN_SHEET> OF <TOTAL_DESIGN_SHEETS>
J 0
(-500 25);
PAINT ORANGE (-500 25);
FORCEPROP 2 LAST CUSTOM_TXT_CDS <CON_LAST_MODIFIED>
J 0
(-1925 350);
PAINT ORANGE (-1925 350);
FORCEPROP 1 LAST SCH_ADDRESS2 P.O. BOX 58119
J 0
(-3975 75);
DISPLAY 0.872340 (-3975 75);
PAINT GREEN (-3975 75);
FORCEPROP 1 LAST SCH_DEPT UNKNOWN
J 1
(-4450 100);
DISPLAY 1.255319 (-4450 100);
PAINT ORANGE (-4450 100);
FORCEPROP 1 LAST SCH_REV 0.1
J 0
(-250 150);
DISPLAY 1.170213 (-250 150);
PAINT GREEN (-250 150);
FORCEPROP 1 LAST SCH_NUMBER 000000-000
J 0
(-1300 150);
DISPLAY 1.702128 (-1300 150);
PAINT GREEN (-1300 150);
FORCEPROP 1 LAST SCH_ADDRESS3 Santa Clara, CA 95052-8119
J 0
(-3975 25);
DISPLAY 0.872340 (-3975 25);
PAINT GREEN (-3975 25);
FORCEPROP 1 LAST SCH_ADDRESS1 2200 Mission College Blvd.
J 0
(-3975 125);
DISPLAY 0.872340 (-3975 125);
PAINT GREEN (-3975 125);
FORCEPROP 1 LAST SCH_TITLE TPM boot circuit
J 0
(-7950 50);
DISPLAY 2.468085 (-7950 50);
PAINT ORANGE (-7950 50);
FORCEPROP 1 LAST COMMENT_BODY TRUE
J 0
(12 12);
DISPLAY 0.468085 (12 12);
PAINT GREEN (12 12);
DISPLAY INVISIBLE (12 12);
FORCEPROP 2 LAST CDS_LIB mstr_symbols
J 0
(0 0);
PAINT MONO (0 0);
DISPLAY INVISIBLE (0 0);
FORCEPROP 2 LAST PAGE_BORDER TRUE
J 0
(-7890 5250);
DISPLAY 0.638298 (-7890 5250);
PAINT PINK (-7890 5250);
DISPLAY INVISIBLE (-7890 5250);
FORCEPROP 2 LAST CDS_XR_PAGE_TITLE CR-249 : @BASEBOARD_FAB2_LIB.BASEBOARD_FAB2(SCH_1):PAGE249
J 0
(-7890 5250);
DISPLAY 0.638298 (-7890 5250);
PAINT PINK (-7890 5250);
DISPLAY INVISIBLE (-7890 5250);
WIRE 16 -1 (-4550 3875)(-4550 3675);
WIRE 16 -1 (-6325 1825)(-6325 1725);
WIRE 16 -1 (-6325 1725)(-5875 1725);
WIRE 16 -1 (-5875 2050)(-5875 1725);
WIRE 16 -1 (-5875 1725)(-5875 1600);
WIRE 16 -1 (-3300 2300)(-3300 2150);
WIRE 16 -1 (-5875 2925)(-5875 3000);
WIRE 16 -1 (-3950 4025)(-3950 3725);
WIRE 16 -1 (-3300 2800)(-3300 3075);
WIRE 16 -1 (-3300 3075)(-2975 3075);
WIRE 16 -1 (-2975 3050)(-2975 3075);
WIRE 16 -1 (-2975 3075)(-2975 3100);
WIRE 16 -1 (-2975 2850)(-2975 2800);
WIRE 16 -1 (-3950 4525)(-3950 4625);
WIRE 16 -1 (-4550 4625)(-3950 4625);
WIRE 16 -1 (-4550 4525)(-4550 4625);
WIRE 16 -1 (-4550 4675)(-4550 4625);
WIRE 16 -1 (-6925 1850)(-6925 1675);
WIRE 16 -1 (-4225 2200)(-4225 2025);
WIRE 16 -1 (-4225 2875)(-4225 3050);
WIRE 16 -1 (-3025 4325)(-3950 4325);
FORCEPROP 2 LAST SIG_NAME RST_BMC_SRST_N
J 0
(-3785 4335);
DISPLAY 0.680851 (-3785 4335);
PAINT ORANGE (-3785 4335);
WIRE 16 -1 (-3950 4225)(-3950 4325);
WIRE 16 -1 (-4550 4125)(-4100 4125);
FORCEPROP 2 LAST SIG_NAME FM_TPM_PRES_RST
J 0
(-4485 4135);
DISPLAY 0.680851 (-4485 4135);
PAINT ORANGE (-4485 4135);
FORCEPROP 2 LASTPROP $XRERR UNIQUE?
J 0
(-4725 4135);
DISPLAY 0.638298 (-4725 4135);
PAINT MONO (-4725 4135);
DISPLAY INVISIBLE (-4725 4135);
WIRE 16 -1 (-4550 4125)(-4550 4275);
WIRE 16 -1 (-4550 4075)(-4550 4125);
WIRE 3 2175 (-7725 4875)(-1300 4875);
WIRE 3 2175 (-7725 4875)(-7725 1425);
WIRE 3 2175 (-1300 4875)(-1300 1425);
WIRE 3 2175 (-7725 1425)(-1300 1425);
WIRE 16 -1 (-3925 3350)(-3925 2600);
WIRE 16 -1 (-5575 3350)(-3925 3350);
WIRE 16 -1 (-3925 2600)(-3500 2600);
WIRE 16 -1 (-5575 3975)(-5575 3350);
WIRE 16 -1 (-5575 2600)(-5575 3350);
WIRE 16 -1 (-5875 2600)(-5575 2600);
WIRE 16 -1 (-5500 3975)(-5575 3975);
WIRE 16 -1 (-5575 3975)(-6100 3975);
FORCEPROP 2 LAST SIG_NAME FM_TPM_PRES_RST_N
J 0
(-6085 3985);
DISPLAY 0.680851 (-6085 3985);
PAINT ORANGE (-6085 3985);
WIRE 16 -1 (-5875 2600)(-5875 2725);
WIRE 16 -1 (-5875 2450)(-5875 2600);
WIRE 16 -1 (-6925 2150)(-6900 2150);
WIRE 16 -1 (-6925 2050)(-6925 2150);
WIRE 16 -1 (-6925 2150)(-7350 2150);
FORCEPROP 2 LAST SIG_NAME BMC_TPM_HW_RST
J 0
(-7335 2160);
DISPLAY 0.680851 (-7335 2160);
PAINT ORANGE (-7335 2160);
WIRE 16 -1 (-2450 2550)(-3000 2550);
FORCEPROP 2 LAST SIG_NAME FM_TPM_PRES_N
J 0
(-2935 2560);
DISPLAY 0.680851 (-2935 2560);
PAINT ORANGE (-2935 2560);
WIRE 16 -1 (-5250 3975)(-4700 3975);
FORCEPROP 2 LAST SIG_NAME FM_TPM_PRES_RST_N_R
J 0
(-5185 3985);
DISPLAY 0.680851 (-5185 3985);
PAINT ORANGE (-5185 3985);
FORCEPROP 2 LASTPROP $XRERR UNIQUE?
J 0
(-5425 3985);
DISPLAY 0.638298 (-5425 3985);
PAINT MONO (-5425 3985);
DISPLAY INVISIBLE (-5425 3985);
WIRE 16 -1 (-6075 2150)(-6325 2150);
WIRE 16 -1 (-6325 2150)(-6700 2150);
FORCEPROP 2 LAST SIG_NAME BMC_TPM_HW_C_RST
J 0
(-6535 2160);
DISPLAY 0.680851 (-6535 2160);
PAINT ORANGE (-6535 2160);
FORCEPROP 2 LASTPROP $XRERR UNIQUE?
J 0
(-6775 2160);
DISPLAY 0.638298 (-6775 2160);
PAINT MONO (-6775 2160);
DISPLAY INVISIBLE (-6775 2160);
WIRE 16 -1 (-6325 2025)(-6325 2150);
WIRE 16 -1 (-4225 2400)(-4225 2500);
WIRE 16 -1 (-4225 2500)(-3500 2500);
FORCEPROP 2 LAST SIG_NAME VREF_2V2
J 0
(-4060 2510);
DISPLAY 0.680851 (-4060 2510);
PAINT ORANGE (-4060 2510);
FORCEPROP 2 LASTPROP $XRERR UNIQUE?
J 0
(-4300 2510);
DISPLAY 0.638298 (-4300 2510);
PAINT MONO (-4300 2510);
DISPLAY INVISIBLE (-4300 2510);
WIRE 16 -1 (-4225 2500)(-4225 2675);
DOT 1 (-5875 2600);
DOT 1 (-6325 2150);
DOT 1 (-4225 2500);
DOT 1 (-5575 3350);
DOT 1 (-5575 3975);
DOT 1 (-4550 4125);
DOT 1 (-5875 1725);
DOT 1 (-2975 3075);
DOT 1 (-6925 2150);
DOT 1 (-4550 4625);
FORCENOTE
TP FAB1 FOR BMC TPM 1120
(-7125 4800) 0;
DISPLAY LEFT (-7125 4800);
DISPLAY 1.021277 (-7125 4800);
PAINT RED (-7125 4800);
QUIT
